(kicad_pcb
	(version 20260206)
	(generator "pcbnew")
	(generator_version "10.0")
	(general
		(thickness 1.6)
		(legacy_teardrops no)
	)
	(paper "A4")
	(title_block
		(title "Bryce Canyon_F.DPB_16315-1-OCP.brd")
		(comment 1 "Bryce Canyon / footprints 1799-1804 of 2223")
	)
	(layers
		(0 "F.Cu" signal "TOP")
		(4 "In1.Cu" signal "L2GND")
		(6 "In2.Cu" signal "L3")
		(8 "In3.Cu" signal "L4GND")
		(10 "In4.Cu" signal "L5")
		(12 "In5.Cu" signal "L6VCC")
		(14 "In6.Cu" signal "L7VCC")
		(16 "In7.Cu" signal "L8")
		(18 "In8.Cu" signal "L9GND")
		(20 "In9.Cu" signal "L10")
		(22 "In10.Cu" signal "L11GND")
		(2 "B.Cu" signal "BOTTOM")
		(9 "F.Adhes" user "F.Adhesive")
		(11 "B.Adhes" user "B.Adhesive")
		(13 "F.Paste" user "Package Geometry/Pastemask Top")
		(15 "B.Paste" user "Package Geometry/Pastemask Bottom")
		(5 "F.SilkS" user "Ref Des/Silkscreen Top")
		(7 "B.SilkS" user "Ref Des/Silkscreen Bottom")
		(1 "F.Mask" user "Board Geometry/Soldermask Top")
		(3 "B.Mask" user "Board Geometry/Soldermask Bottom")
		(17 "Dwgs.User" user "User.Drawings")
		(19 "Cmts.User" user "User.Comments")
		(21 "Eco1.User" user "User.Eco1")
		(23 "Eco2.User" user "User.Eco2")
		(25 "Edge.Cuts" user "Board Geometry/Outline")
		(27 "Margin" user)
		(31 "F.CrtYd" user "Package Geometry/Place Bound Top")
		(29 "B.CrtYd" user "Package Geometry/Place Bound Bottom")
		(35 "F.Fab" user "Ref Des/Assembly Top")
		(33 "B.Fab" user "Ref Des/Assembly Bottom")
	)
	(footprint ""
		(layer "F.Cu")
		(at 333.248 -42.585894 180)
		(property "Reference" "R828"
			(at 0 0 180)
			(layer "F.SilkS")
			(hide yes)
			(effects
				(font
					(size 1.27 1.27)
				)
			)
		)
		(property "Value" "1KR2F-3-GP"
			(at 0.064008 -3.993896 180)
			(unlocked yes)
			(layer "F.Fab")
			(hide yes)
			(effects
				(font
					(size 1.016 1.016)
					(thickness 0.1524)
				)
			)
		)
		(property "Device Type" "R402H16"
			(at 0.064008 -5.517896 180)
			(unlocked yes)
			(layer "F.Fab")
			(hide yes)
			(effects
				(font
					(size 1.016 1.016)
					(thickness 0.1524)
				)
			)
		)
		(duplicate_pad_numbers_are_jumpers no)
		(fp_line
			(start 0.508 -0.9398)
			(end -0.508 -0.9398)
			(stroke
				(width 0.1524)
				(type default)
			)
			(layer "F.SilkS")
		)
		(fp_line
			(start -0.508 -0.9398)
			(end -0.508 0.9398)
			(stroke
				(width 0.1524)
				(type default)
			)
			(layer "F.SilkS")
		)
		(fp_rect
			(start -0.508 0.9398)
			(end 0.508 -0.9398)
			(stroke
				(width 0)
				(type default)
			)
			(fill no)
			(layer "F.CrtYd")
		)
		(fp_rect
			(start -0.508 0.9398)
			(end 0.508 -0.9398)
			(stroke
				(width 0)
				(type default)
			)
			(fill no)
			(layer "F.Fab")
		)
		(pad "1" smd custom
			(at 0 -0.4445 180)
			(size 0.1397 0.1397)
			(layers "F.Cu" "F.Mask" "F.Paste")
			(net "P3V3_STBY_A")
			(options
				(clearance outline)
				(anchor circle)
			)
			(primitives
				(gr_poly
					(pts
						(arc
							(start -0.1778 -0.2794)
							(mid -0.249642 -0.249642)
							(end -0.2794 -0.1778)
						)
						(arc
							(start -0.2794 0.1778)
							(mid -0.249642 0.249642)
							(end -0.1778 0.2794)
						)
						(arc
							(start 0.1778 0.2794)
							(mid 0.249642 0.249642)
							(end 0.2794 0.1778)
						)
						(arc
							(start 0.2794 -0.1778)
							(mid 0.249642 -0.249642)
							(end 0.1778 -0.2794)
						)
					)
					(width 0)
					(fill yes)
				)
			)
		)
		(pad "2" smd custom
			(at 0 0.4445 180)
			(size 0.1397 0.1397)
			(layers "F.Cu" "F.Mask" "F.Paste")
			(net "SW_PWR_R_HDD30")
			(options
				(clearance outline)
				(anchor circle)
			)
			(primitives
				(gr_poly
					(pts
						(arc
							(start -0.1778 -0.2794)
							(mid -0.249642 -0.249642)
							(end -0.2794 -0.1778)
						)
						(arc
							(start -0.2794 0.1778)
							(mid -0.249642 0.249642)
							(end -0.1778 0.2794)
						)
						(arc
							(start 0.1778 0.2794)
							(mid 0.249642 0.249642)
							(end 0.2794 0.1778)
						)
						(arc
							(start 0.2794 -0.1778)
							(mid 0.249642 -0.249642)
							(end 0.1778 -0.2794)
						)
					)
					(width 0)
					(fill yes)
				)
			)
		)
	)
	(footprint ""
		(layer "F.Cu")
		(at 353.184714 -159.219392 -90)
		(property "Reference" "C285"
			(at 0 0 270)
			(layer "F.SilkS")
			(hide yes)
			(effects
				(font
					(size 1.27 1.27)
				)
			)
		)
		(property "Value" "SCD01U16V1KX-GP"
			(at -2.8321 -1.7399 270)
			(unlocked yes)
			(layer "F.Fab")
			(hide yes)
			(effects
				(font
					(size 1.016 1.016)
					(thickness 0.1524)
				)
			)
		)
		(property "Device Type" "C0201H13"
			(at -2.8321 -3.2639 270)
			(unlocked yes)
			(layer "F.Fab")
			(hide yes)
			(effects
				(font
					(size 1.016 1.016)
					(thickness 0.1524)
				)
			)
		)
		(duplicate_pad_numbers_are_jumpers no)
		(fp_rect
			(start -0.2794 0.6477)
			(end 0.2794 -0.6477)
			(stroke
				(width 0)
				(type default)
			)
			(fill no)
			(layer "F.CrtYd")
		)
		(fp_rect
			(start -0.2794 0.6477)
			(end 0.2794 -0.6477)
			(stroke
				(width 0)
				(type default)
			)
			(fill no)
			(layer "F.Fab")
		)
		(pad "1" smd custom
			(at 0 -0.2794 270)
			(size 0.0762 0.0762)
			(layers "F.Cu" "F.Mask" "F.Paste")
			(net "SAS_HDD_RX_N19")
			(options
				(clearance outline)
				(anchor circle)
			)
			(primitives
				(gr_poly
					(pts
						(arc
							(start 0.1524 -0.127)
							(mid 0.137521 -0.162921)
							(end 0.1016 -0.1778)
						)
						(arc
							(start -0.1016 -0.1778)
							(mid -0.137521 -0.162921)
							(end -0.1524 -0.127)
						)
						(arc
							(start -0.1524 0.127)
							(mid -0.137521 0.162921)
							(end -0.1016 0.1778)
						)
						(arc
							(start 0.1016 0.1778)
							(mid 0.137521 0.162921)
							(end 0.1524 0.127)
						)
					)
					(width 0)
					(fill yes)
				)
			)
		)
		(pad "2" smd custom
			(at 0 0.2794 270)
			(size 0.0762 0.0762)
			(layers "F.Cu" "F.Mask" "F.Paste")
			(net "PHY_SCC_A_TO_DRV_A_19_DN")
			(options
				(clearance outline)
				(anchor circle)
			)
			(primitives
				(gr_poly
					(pts
						(arc
							(start 0.1524 -0.127)
							(mid 0.137521 -0.162921)
							(end 0.1016 -0.1778)
						)
						(arc
							(start -0.1016 -0.1778)
							(mid -0.137521 -0.162921)
							(end -0.1524 -0.127)
						)
						(arc
							(start -0.1524 0.127)
							(mid -0.137521 0.162921)
							(end -0.1016 0.1778)
						)
						(arc
							(start 0.1016 0.1778)
							(mid 0.137521 0.162921)
							(end 0.1524 0.127)
						)
					)
					(width 0)
					(fill yes)
				)
			)
		)
	)
	(footprint ""
		(layer "F.Cu")
		(at 424.469052 -296.842942 180)
		(property "Reference" "C157"
			(at 0 0 180)
			(layer "F.SilkS")
			(hide yes)
			(effects
				(font
					(size 1.27 1.27)
				)
			)
		)
		(property "Value" "SC1U16V3KX-5GP"
			(at 0 -2.8194 180)
			(unlocked yes)
			(layer "F.Fab")
			(hide yes)
			(effects
				(font
					(size 1.016 1.016)
					(thickness 0.1524)
				)
			)
		)
		(property "Device Type" "C603H36"
			(at 0 -4.3434 180)
			(unlocked yes)
			(layer "F.Fab")
			(hide yes)
			(effects
				(font
					(size 1.016 1.016)
					(thickness 0.1524)
				)
			)
		)
		(duplicate_pad_numbers_are_jumpers no)
		(fp_line
			(start 0.508 0)
			(end -0.508 0)
			(stroke
				(width 0.2032)
				(type default)
			)
			(layer "F.SilkS")
		)
		(fp_rect
			(start -0.5842 1.3335)
			(end 0.5842 -1.3335)
			(stroke
				(width 0)
				(type default)
			)
			(fill no)
			(layer "F.CrtYd")
		)
		(fp_rect
			(start -0.5842 1.3335)
			(end 0.5842 -1.3335)
			(stroke
				(width 0)
				(type default)
			)
			(fill no)
			(layer "F.Fab")
		)
		(pad "1" smd custom
			(at 0 -0.762 180)
			(size 0.2159 0.2159)
			(layers "F.Cu" "F.Mask" "F.Paste")
			(net "P5V_HDD9")
			(options
				(clearance outline)
				(anchor circle)
			)
			(primitives
				(gr_poly
					(pts
						(arc
							(start -0.3302 -0.4318)
							(mid -0.402042 -0.402042)
							(end -0.4318 -0.3302)
						)
						(arc
							(start -0.4318 0.3302)
							(mid -0.402042 0.402042)
							(end -0.3302 0.4318)
						)
						(arc
							(start 0.3302 0.4318)
							(mid 0.402042 0.402042)
							(end 0.4318 0.3302)
						)
						(arc
							(start 0.4318 -0.3302)
							(mid 0.402042 -0.402042)
							(end 0.3302 -0.4318)
						)
					)
					(width 0)
					(fill yes)
				)
			)
		)
		(pad "2" smd custom
			(at 0 0.762 180)
			(size 0.2159 0.2159)
			(layers "F.Cu" "F.Mask" "F.Paste")
			(net "GND")
			(options
				(clearance outline)
				(anchor circle)
			)
			(primitives
				(gr_poly
					(pts
						(arc
							(start -0.3302 -0.4318)
							(mid -0.402042 -0.402042)
							(end -0.4318 -0.3302)
						)
						(arc
							(start -0.4318 0.3302)
							(mid -0.402042 0.402042)
							(end -0.3302 0.4318)
						)
						(arc
							(start 0.3302 0.4318)
							(mid 0.402042 0.402042)
							(end 0.4318 0.3302)
						)
						(arc
							(start 0.4318 -0.3302)
							(mid 0.402042 -0.402042)
							(end 0.3302 -0.4318)
						)
					)
					(width 0)
					(fill yes)
				)
			)
		)
	)
	(footprint ""
		(layer "F.Cu")
		(at 353.184714 -43.660568 -90)
		(property "Reference" "C442"
			(at 0 0 270)
			(layer "F.SilkS")
			(hide yes)
			(effects
				(font
					(size 1.27 1.27)
				)
			)
		)
		(property "Value" "SCD01U16V1KX-GP"
			(at -2.8321 -1.7399 270)
			(unlocked yes)
			(layer "F.Fab")
			(hide yes)
			(effects
				(font
					(size 1.016 1.016)
					(thickness 0.1524)
				)
			)
		)
		(property "Device Type" "C0201H13"
			(at -2.8321 -3.2639 270)
			(unlocked yes)
			(layer "F.Fab")
			(hide yes)
			(effects
				(font
					(size 1.016 1.016)
					(thickness 0.1524)
				)
			)
		)
		(duplicate_pad_numbers_are_jumpers no)
		(fp_rect
			(start -0.2794 0.6477)
			(end 0.2794 -0.6477)
			(stroke
				(width 0)
				(type default)
			)
			(fill no)
			(layer "F.CrtYd")
		)
		(fp_rect
			(start -0.2794 0.6477)
			(end 0.2794 -0.6477)
			(stroke
				(width 0)
				(type default)
			)
			(fill no)
			(layer "F.Fab")
		)
		(pad "1" smd custom
			(at 0 -0.2794 270)
			(size 0.0762 0.0762)
			(layers "F.Cu" "F.Mask" "F.Paste")
			(net "SAS_HDD_RX_P31")
			(options
				(clearance outline)
				(anchor circle)
			)
			(primitives
				(gr_poly
					(pts
						(arc
							(start 0.1524 -0.127)
							(mid 0.137521 -0.162921)
							(end 0.1016 -0.1778)
						)
						(arc
							(start -0.1016 -0.1778)
							(mid -0.137521 -0.162921)
							(end -0.1524 -0.127)
						)
						(arc
							(start -0.1524 0.127)
							(mid -0.137521 0.162921)
							(end -0.1016 0.1778)
						)
						(arc
							(start 0.1016 0.1778)
							(mid 0.137521 0.162921)
							(end 0.1524 0.127)
						)
					)
					(width 0)
					(fill yes)
				)
			)
		)
		(pad "2" smd custom
			(at 0 0.2794 270)
			(size 0.0762 0.0762)
			(layers "F.Cu" "F.Mask" "F.Paste")
			(net "PHY_SCC_A_TO_DRV_A_31_DP")
			(options
				(clearance outline)
				(anchor circle)
			)
			(primitives
				(gr_poly
					(pts
						(arc
							(start 0.1524 -0.127)
							(mid 0.137521 -0.162921)
							(end 0.1016 -0.1778)
						)
						(arc
							(start -0.1016 -0.1778)
							(mid -0.137521 -0.162921)
							(end -0.1524 -0.127)
						)
						(arc
							(start -0.1524 0.127)
							(mid -0.137521 0.162921)
							(end -0.1016 0.1778)
						)
						(arc
							(start 0.1016 0.1778)
							(mid 0.137521 0.162921)
							(end 0.1524 0.127)
						)
					)
					(width 0)
					(fill yes)
				)
			)
		)
	)
	(footprint ""
		(layer "F.Cu")
		(at 236.869986 -346.782136)
		(property "Reference" "R162"
			(at 0 0 0)
			(layer "F.SilkS")
			(hide yes)
			(effects
				(font
					(size 1.27 1.27)
				)
			)
		)
		(property "Value" "10KR2F-2-GP"
			(at 0.064008 -3.993896 0)
			(unlocked yes)
			(layer "F.Fab")
			(hide yes)
			(effects
				(font
					(size 1.016 1.016)
					(thickness 0.1524)
				)
			)
		)
		(property "Device Type" "R402H16"
			(at 0.064008 -5.517896 0)
			(unlocked yes)
			(layer "F.Fab")
			(hide yes)
			(effects
				(font
					(size 1.016 1.016)
					(thickness 0.1524)
				)
			)
		)
		(duplicate_pad_numbers_are_jumpers no)
		(fp_line
			(start -0.508 -0.9398)
			(end -0.508 0.9398)
			(stroke
				(width 0.1524)
				(type default)
			)
			(layer "F.SilkS")
		)
		(fp_line
			(start 0.508 -0.9398)
			(end -0.508 -0.9398)
			(stroke
				(width 0.1524)
				(type default)
			)
			(layer "F.SilkS")
		)
		(fp_rect
			(start -0.508 0.9398)
			(end 0.508 -0.9398)
			(stroke
				(width 0)
				(type default)
			)
			(fill no)
			(layer "F.CrtYd")
		)
		(fp_rect
			(start -0.508 0.9398)
			(end 0.508 -0.9398)
			(stroke
				(width 0)
				(type default)
			)
			(fill no)
			(layer "F.Fab")
		)
		(pad "1" smd custom
			(at 0 -0.4445)
			(size 0.1397 0.1397)
			(layers "F.Cu" "F.Mask" "F.Paste")
			(net "P5V_A_2_SENSE")
			(options
				(clearance outline)
				(anchor circle)
			)
			(primitives
				(gr_poly
					(pts
						(arc
							(start -0.1778 -0.2794)
							(mid -0.249642 -0.249642)
							(end -0.2794 -0.1778)
						)
						(arc
							(start -0.2794 0.1778)
							(mid -0.249642 0.249642)
							(end -0.1778 0.2794)
						)
						(arc
							(start 0.1778 0.2794)
							(mid 0.249642 0.249642)
							(end 0.2794 0.1778)
						)
						(arc
							(start 0.2794 -0.1778)
							(mid 0.249642 -0.249642)
							(end 0.1778 -0.2794)
						)
					)
					(width 0)
					(fill yes)
				)
			)
		)
		(pad "2" smd custom
			(at 0 0.4445)
			(size 0.1397 0.1397)
			(layers "F.Cu" "F.Mask" "F.Paste")
			(net "GND")
			(options
				(clearance outline)
				(anchor circle)
			)
			(primitives
				(gr_poly
					(pts
						(arc
							(start -0.1778 -0.2794)
							(mid -0.249642 -0.249642)
							(end -0.2794 -0.1778)
						)
						(arc
							(start -0.2794 0.1778)
							(mid -0.249642 0.249642)
							(end -0.1778 0.2794)
						)
						(arc
							(start 0.1778 0.2794)
							(mid 0.249642 0.249642)
							(end 0.2794 0.1778)
						)
						(arc
							(start 0.2794 -0.1778)
							(mid 0.249642 -0.249642)
							(end 0.1778 -0.2794)
						)
					)
					(width 0)
					(fill yes)
				)
			)
		)
	)
	(footprint ""
		(layer "F.Cu")
		(at 115.080796 -62.778894 -90)
		(property "Reference" "C391"
			(at 0 0 270)
			(layer "F.SilkS")
			(hide yes)
			(effects
				(font
					(size 1.27 1.27)
				)
			)
		)
		(property "Value" "SC1U16V3KX-5GP"
			(at 0 -2.8194 270)
			(unlocked yes)
			(layer "F.Fab")
			(hide yes)
			(effects
				(font
					(size 1.016 1.016)
					(thickness 0.1524)
				)
			)
		)
		(property "Device Type" "C603H36"
			(at 0 -4.3434 270)
			(unlocked yes)
			(layer "F.Fab")
			(hide yes)
			(effects
				(font
					(size 1.016 1.016)
					(thickness 0.1524)
				)
			)
		)
		(duplicate_pad_numbers_are_jumpers no)
		(fp_line
			(start 0.508 0)
			(end -0.508 0)
			(stroke
				(width 0.2032)
				(type default)
			)
			(layer "F.SilkS")
		)
		(fp_rect
			(start -0.5842 1.3335)
			(end 0.5842 -1.3335)
			(stroke
				(width 0)
				(type default)
			)
			(fill no)
			(layer "F.CrtYd")
		)
		(fp_rect
			(start -0.5842 1.3335)
			(end 0.5842 -1.3335)
			(stroke
				(width 0)
				(type default)
			)
			(fill no)
			(layer "F.Fab")
		)
		(pad "1" smd custom
			(at 0 -0.762 270)
			(size 0.2159 0.2159)
			(layers "F.Cu" "F.Mask" "F.Paste")
			(net "P5V_HDD27")
			(options
				(clearance outline)
				(anchor circle)
			)
			(primitives
				(gr_poly
					(pts
						(arc
							(start -0.3302 -0.4318)
							(mid -0.402042 -0.402042)
							(end -0.4318 -0.3302)
						)
						(arc
							(start -0.4318 0.3302)
							(mid -0.402042 0.402042)
							(end -0.3302 0.4318)
						)
						(arc
							(start 0.3302 0.4318)
							(mid 0.402042 0.402042)
							(end 0.4318 0.3302)
						)
						(arc
							(start 0.4318 -0.3302)
							(mid 0.402042 -0.402042)
							(end 0.3302 -0.4318)
						)
					)
					(width 0)
					(fill yes)
				)
			)
		)
		(pad "2" smd custom
			(at 0 0.762 270)
			(size 0.2159 0.2159)
			(layers "F.Cu" "F.Mask" "F.Paste")
			(net "GND")
			(options
				(clearance outline)
				(anchor circle)
			)
			(primitives
				(gr_poly
					(pts
						(arc
							(start -0.3302 -0.4318)
							(mid -0.402042 -0.402042)
							(end -0.4318 -0.3302)
						)
						(arc
							(start -0.4318 0.3302)
							(mid -0.402042 0.402042)
							(end -0.3302 0.4318)
						)
						(arc
							(start 0.3302 0.4318)
							(mid 0.402042 0.402042)
							(end 0.4318 0.3302)
						)
						(arc
							(start 0.4318 -0.3302)
							(mid 0.402042 -0.402042)
							(end 0.3302 -0.4318)
						)
					)
					(width 0)
					(fill yes)
				)
			)
		)
	)
)
